(kicad_pcb
	(version 20260206)
	(generator "pcbnew")
	(generator_version "10.0")
	(general
		(thickness 1.6)
		(legacy_teardrops no)
	)
	(paper "A4")
	(title_block
		(title "9054_F0T_PDB_BD_GPU_F_V04_1213_1550_OCP.brd")
		(comment 1 "Grand Teton / footprints 277-279 of 608")
	)
	(layers
		(0 "F.Cu" signal "TOP")
		(4 "In1.Cu" signal "GND")
		(6 "In2.Cu" signal "IN1")
		(8 "In3.Cu" signal "GND1")
		(10 "In4.Cu" signal "VCC")
		(12 "In5.Cu" signal "VCC1")
		(14 "In6.Cu" signal "GND2")
		(16 "In7.Cu" signal "IN2")
		(18 "In8.Cu" signal "GND3")
		(2 "B.Cu" signal "BOTTOM")
		(9 "F.Adhes" user "F.Adhesive")
		(11 "B.Adhes" user "B.Adhesive")
		(13 "F.Paste" user "Package Geometry/Pastemask Top")
		(15 "B.Paste" user "Package Geometry/Pastemask Bottom")
		(5 "F.SilkS" user "Ref Des/Silkscreen Top")
		(7 "B.SilkS" user "Ref Des/Silkscreen Bottom")
		(1 "F.Mask" user "Board Geometry/Soldermask Top")
		(3 "B.Mask" user "Board Geometry/Soldermask Bottom")
		(17 "Dwgs.User" user "User.Drawings")
		(19 "Cmts.User" user "User.Comments")
		(21 "Eco1.User" user "User.Eco1")
		(23 "Eco2.User" user "User.Eco2")
		(25 "Edge.Cuts" user "Board Geometry/Outline")
		(27 "Margin" user)
		(31 "F.CrtYd" user "Package Geometry/Place Bound Top")
		(29 "B.CrtYd" user "Package Geometry/Place Bound Bottom")
		(35 "F.Fab" user "Ref Des/Assembly Top")
		(33 "B.Fab" user "Ref Des/Assembly Bottom")
	)
	(footprint ""
		(layer "F.Cu")
		(at 391.199878 -156.830014 180)
		(property "Reference" "J1"
			(at 3.976878 -7.758684 0)
			(unlocked yes)
			(layer "F.SilkS")
			(effects
				(font
					(size 0.7874 0.5842)
					(thickness 0.1524)
				)
				(justify left)
			)
		)
		(property "Value" ""
			(at 0 0 180)
			(layer "F.Fab")
			(effects
				(font
					(size 1.27 1.27)
				)
			)
		)
		(duplicate_pad_numbers_are_jumpers no)
		(fp_line
			(start 12.925044 28.450032)
			(end -4.92506 28.450032)
			(stroke
				(width 0.1524)
				(type default)
			)
			(layer "F.SilkS")
		)
		(fp_line
			(start 12.925044 -6.849872)
			(end 12.925044 28.450032)
			(stroke
				(width 0.1524)
				(type default)
			)
			(layer "F.SilkS")
		)
		(fp_line
			(start 9.92505 25.450038)
			(end -1.925066 25.450038)
			(stroke
				(width 0.1524)
				(type default)
			)
			(layer "F.SilkS")
		)
		(fp_line
			(start 9.92505 -3.850132)
			(end 9.92505 25.450038)
			(stroke
				(width 0.1524)
				(type default)
			)
			(layer "F.SilkS")
		)
		(fp_line
			(start -1.925066 25.450038)
			(end -1.925066 -3.850132)
			(stroke
				(width 0.1524)
				(type default)
			)
			(layer "F.SilkS")
		)
		(fp_line
			(start -1.925066 14.99997)
			(end 9.92505 14.99997)
			(stroke
				(width 0.1524)
				(type default)
			)
			(layer "F.SilkS")
		)
		(fp_line
			(start -1.925066 -3.850132)
			(end 9.92505 -3.850132)
			(stroke
				(width 0.1524)
				(type default)
			)
			(layer "F.SilkS")
		)
		(fp_line
			(start -4.92506 28.450032)
			(end -4.92506 -6.849872)
			(stroke
				(width 0.1524)
				(type default)
			)
			(layer "F.SilkS")
		)
		(fp_line
			(start -4.92506 -6.849872)
			(end 12.925044 -6.849872)
			(stroke
				(width 0.1524)
				(type default)
			)
			(layer "F.SilkS")
		)
		(fp_poly
			(pts
				(xy 0.054864 -0.8636) (xy 0.816864 -2.7686) (xy -0.707136 -2.7686)
			)
			(stroke
				(width 0)
				(type default)
			)
			(fill yes)
			(layer "F.SilkS")
		)
		(fp_line
			(start 12.925044 28.450032)
			(end -4.92506 28.450032)
			(stroke
				(width 0.1524)
				(type default)
			)
			(layer "B.SilkS")
		)
		(fp_line
			(start 12.925044 -6.849872)
			(end 12.925044 28.450032)
			(stroke
				(width 0.1524)
				(type default)
			)
			(layer "B.SilkS")
		)
		(fp_line
			(start -4.92506 28.450032)
			(end -4.92506 -6.849872)
			(stroke
				(width 0.1524)
				(type default)
			)
			(layer "B.SilkS")
		)
		(fp_line
			(start -4.92506 -6.849872)
			(end 12.925044 -6.849872)
			(stroke
				(width 0.1524)
				(type default)
			)
			(layer "B.SilkS")
		)
		(fp_line
			(start 12.925044 28.450032)
			(end -4.92506 28.450032)
			(stroke
				(width 0.1)
				(type default)
			)
			(layer "B.Fab")
		)
		(fp_line
			(start 12.925044 -6.849872)
			(end 12.925044 28.450032)
			(stroke
				(width 0.1)
				(type default)
			)
			(layer "B.Fab")
		)
		(fp_line
			(start -4.92506 28.450032)
			(end -4.92506 -6.849872)
			(stroke
				(width 0.1)
				(type default)
			)
			(layer "B.Fab")
		)
		(fp_line
			(start -4.92506 -6.849872)
			(end 12.925044 -6.849872)
			(stroke
				(width 0.1)
				(type default)
			)
			(layer "B.Fab")
		)
		(fp_line
			(start 9.92505 25.450038)
			(end -1.925066 25.450038)
			(stroke
				(width 0.1)
				(type default)
			)
			(layer "F.Fab")
		)
		(fp_line
			(start 9.92505 -3.850132)
			(end 9.92505 25.450038)
			(stroke
				(width 0.1)
				(type default)
			)
			(layer "F.Fab")
		)
		(fp_line
			(start -1.925066 25.450038)
			(end -1.925066 -3.850132)
			(stroke
				(width 0.1)
				(type default)
			)
			(layer "F.Fab")
		)
		(fp_line
			(start -1.925066 -3.850132)
			(end 9.92505 -3.850132)
			(stroke
				(width 0.1)
				(type default)
			)
			(layer "F.Fab")
		)
		(fp_poly
			(pts
				(xy -2.108708 0) (xy -4.013708 -0.762) (xy -4.013708 0.762)
			)
			(stroke
				(width 0)
				(type default)
			)
			(fill yes)
			(layer "F.Fab")
		)
		(fp_text user "PRESS-FIT"
			(at 9.564878 -5.636514 0)
			(unlocked yes)
			(layer "F.SilkS")
			(effects
				(font
					(size 1.27 0.9652)
					(thickness 0.1524)
				)
				(justify left)
			)
		)
		(fp_text user "PRESS-FIT"
			(at -3.382772 -4.811014 270)
			(unlocked yes)
			(layer "B.SilkS")
			(effects
				(font
					(size 1.905 1.4224)
					(thickness 0.1524)
				)
				(justify left mirror)
			)
		)
		(fp_text user "PRESS-FIT"
			(at 11.346942 12.866116 90)
			(unlocked yes)
			(layer "B.Fab")
			(effects
				(font
					(size 1.905 1.4224)
					(thickness 0.1524)
				)
				(justify left mirror)
			)
		)
		(fp_text user "PRESS-FIT"
			(at 11.346942 -3.872484 90)
			(unlocked yes)
			(layer "F.Fab")
			(effects
				(font
					(size 1.905 1.4224)
					(thickness 0.1524)
				)
				(justify left)
			)
		)
		(pad "" np_thru_hole circle
			(at 3.999992 5.500116 180)
			(size 2.1082 2.1082)
			(drill 2.1082)
			(layers "*.Cu" "*.Mask")
			(clearance 0.381)
			(thermal_gap 0.381)
		)
		(pad "A1" thru_hole rect
			(at 0 0 180)
			(size 1.156208 1.156208)
			(drill 0.749808)
			(layers "*.Cu" "*.Mask")
			(remove_unused_layers no)
			(net "P52V_HS1")
			(clearance 0.0508)
			(thermal_gap 0.0508)
			(padstack
				(mode front_inner_back)
				(layer "Inner"
					(shape circle)
					(size 1.156208 1.156208)
					(clearance 0.0508)
				)
				(layer "B.Cu"
					(shape rect)
					(size 1.156208 1.156208)
					(clearance 0.0508)
				)
			)
		)
		(pad "A2" thru_hole circle
			(at 0 1.999996 180)
			(size 1.156208 1.156208)
			(drill 0.749808)
			(layers "*.Cu" "*.Mask")
			(remove_unused_layers no)
			(net "P52V_HS1")
			(clearance 0.0508)
			(thermal_gap 0.0508)
		)
		(pad "A3" thru_hole circle
			(at 0 3.999992 180)
			(size 1.156208 1.156208)
			(drill 0.749808)
			(layers "*.Cu" "*.Mask")
			(remove_unused_layers no)
			(net "P52V_HS1")
			(clearance 0.0508)
			(thermal_gap 0.0508)
		)
		(pad "A4" thru_hole circle
			(at 1.999996 0 180)
			(size 1.156208 1.156208)
			(drill 0.749808)
			(layers "*.Cu" "*.Mask")
			(remove_unused_layers no)
			(net "P52V_HS1")
			(clearance 0.0508)
			(thermal_gap 0.0508)
		)
		(pad "A5" thru_hole circle
			(at 1.999996 1.999996 180)
			(size 1.156208 1.156208)
			(drill 0.749808)
			(layers "*.Cu" "*.Mask")
			(remove_unused_layers no)
			(net "P52V_HS1")
			(clearance 0.0508)
			(thermal_gap 0.0508)
		)
		(pad "A6" thru_hole circle
			(at 1.999996 3.999992 180)
			(size 1.156208 1.156208)
			(drill 0.749808)
			(layers "*.Cu" "*.Mask")
			(remove_unused_layers no)
			(net "P52V_HS1")
			(clearance 0.0508)
			(thermal_gap 0.0508)
		)
		(pad "B1" thru_hole circle
			(at 7.999984 0 180)
			(size 1.156208 1.156208)
			(drill 0.749808)
			(layers "*.Cu" "*.Mask")
			(remove_unused_layers no)
			(net "P52V_HS1")
			(clearance 0.0508)
			(thermal_gap 0.0508)
		)
		(pad "B2" thru_hole circle
			(at 7.999984 1.999996 180)
			(size 1.156208 1.156208)
			(drill 0.749808)
			(layers "*.Cu" "*.Mask")
			(remove_unused_layers no)
			(net "P52V_HS1")
			(clearance 0.0508)
			(thermal_gap 0.0508)
		)
		(pad "B3" thru_hole circle
			(at 7.999984 3.999992 180)
			(size 1.156208 1.156208)
			(drill 0.749808)
			(layers "*.Cu" "*.Mask")
			(remove_unused_layers no)
			(net "P52V_HS1")
			(clearance 0.0508)
			(thermal_gap 0.0508)
		)
		(pad "B4" thru_hole circle
			(at 5.999988 0 180)
			(size 1.156208 1.156208)
			(drill 0.749808)
			(layers "*.Cu" "*.Mask")
			(remove_unused_layers no)
			(net "P52V_HS1")
			(clearance 0.0508)
			(thermal_gap 0.0508)
		)
		(pad "B5" thru_hole circle
			(at 5.999988 1.999996 180)
			(size 1.156208 1.156208)
			(drill 0.749808)
			(layers "*.Cu" "*.Mask")
			(remove_unused_layers no)
			(net "P52V_HS1")
			(clearance 0.0508)
			(thermal_gap 0.0508)
		)
		(pad "B6" thru_hole circle
			(at 5.999988 3.999992 180)
			(size 1.156208 1.156208)
			(drill 0.749808)
			(layers "*.Cu" "*.Mask")
			(remove_unused_layers no)
			(net "P52V_HS1")
			(clearance 0.0508)
			(thermal_gap 0.0508)
		)
		(pad "C1" thru_hole circle
			(at 7.999984 7.999984 180)
			(size 1.156208 1.156208)
			(drill 0.749808)
			(layers "*.Cu" "*.Mask")
			(remove_unused_layers no)
			(net "GND")
			(clearance 0.0508)
			(thermal_gap 0.0508)
		)
		(pad "C2" thru_hole circle
			(at 7.999984 9.99998 180)
			(size 1.156208 1.156208)
			(drill 0.749808)
			(layers "*.Cu" "*.Mask")
			(remove_unused_layers no)
			(net "GND")
			(clearance 0.0508)
			(thermal_gap 0.0508)
		)
		(pad "C3" thru_hole circle
			(at 7.999984 11.999976 180)
			(size 1.156208 1.156208)
			(drill 0.749808)
			(layers "*.Cu" "*.Mask")
			(remove_unused_layers no)
			(net "GND")
			(clearance 0.0508)
			(thermal_gap 0.0508)
		)
		(pad "C4" thru_hole circle
			(at 5.999988 7.999984 180)
			(size 1.156208 1.156208)
			(drill 0.749808)
			(layers "*.Cu" "*.Mask")
			(remove_unused_layers no)
			(net "GND")
			(clearance 0.0508)
			(thermal_gap 0.0508)
		)
		(pad "C5" thru_hole circle
			(at 5.999988 9.99998 180)
			(size 1.156208 1.156208)
			(drill 0.749808)
			(layers "*.Cu" "*.Mask")
			(remove_unused_layers no)
			(net "GND")
			(clearance 0.0508)
			(thermal_gap 0.0508)
		)
		(pad "C6" thru_hole circle
			(at 5.999988 11.999976 180)
			(size 1.156208 1.156208)
			(drill 0.749808)
			(layers "*.Cu" "*.Mask")
			(remove_unused_layers no)
			(net "GND")
			(clearance 0.0508)
			(thermal_gap 0.0508)
		)
		(pad "D1" thru_hole circle
			(at 0 7.999984 180)
			(size 1.156208 1.156208)
			(drill 0.749808)
			(layers "*.Cu" "*.Mask")
			(remove_unused_layers no)
			(net "GND")
			(clearance 0.0508)
			(thermal_gap 0.0508)
		)
		(pad "D2" thru_hole circle
			(at 0 9.99998 180)
			(size 1.156208 1.156208)
			(drill 0.749808)
			(layers "*.Cu" "*.Mask")
			(remove_unused_layers no)
			(net "GND")
			(clearance 0.0508)
			(thermal_gap 0.0508)
		)
		(pad "D3" thru_hole circle
			(at 0 11.999976 180)
			(size 1.156208 1.156208)
			(drill 0.749808)
			(layers "*.Cu" "*.Mask")
			(remove_unused_layers no)
			(net "GND")
			(clearance 0.0508)
			(thermal_gap 0.0508)
		)
		(pad "D4" thru_hole circle
			(at 1.999996 7.999984 180)
			(size 1.156208 1.156208)
			(drill 0.749808)
			(layers "*.Cu" "*.Mask")
			(remove_unused_layers no)
			(net "GND")
			(clearance 0.0508)
			(thermal_gap 0.0508)
		)
		(pad "D5" thru_hole circle
			(at 1.999996 9.99998 180)
			(size 1.156208 1.156208)
			(drill 0.749808)
			(layers "*.Cu" "*.Mask")
			(remove_unused_layers no)
			(net "GND")
			(clearance 0.0508)
			(thermal_gap 0.0508)
		)
		(pad "D6" thru_hole circle
			(at 1.999996 11.999976 180)
			(size 1.156208 1.156208)
			(drill 0.749808)
			(layers "*.Cu" "*.Mask")
			(remove_unused_layers no)
			(net "GND")
			(clearance 0.0508)
			(thermal_gap 0.0508)
		)
		(zone
			(layers "F.Cu" "B.Cu" "In1.Cu" "In2.Cu" "In3.Cu" "In4.Cu" "In5.Cu" "In6.Cu"
				"In7.Cu" "In8.Cu"
			)
			(hatch none 0.5)
			(connect_pads
				(clearance 0)
			)
			(min_thickness 0.25)
			(keepout
				(tracks not_allowed)
				(vias allowed)
				(pads allowed)
				(copperpour not_allowed)
				(footprints allowed)
			)
			(placement
				(enabled no)
				(sheetname "")
			)
			(fill
				(thermal_gap 0.5)
				(thermal_bridge_width 0.5)
				(island_removal_mode 0)
			)
			(polygon
				(pts
					(arc
						(start 388.660386 -162.329876)
						(mid 385.739386 -162.330384)
						(end 388.660386 -162.329876)
					)
				)
			)
		)
		(zone
			(layer "B.Cu")
			(hatch none 0.5)
			(connect_pads
				(clearance 0)
			)
			(min_thickness 0.25)
			(keepout
				(tracks allowed)
				(vias not_allowed)
				(pads allowed)
				(copperpour not_allowed)
				(footprints allowed)
			)
			(placement
				(enabled no)
				(sheetname "")
			)
			(fill
				(thermal_gap 0.5)
				(thermal_bridge_width 0.5)
				(island_removal_mode 0)
			)
			(polygon
				(pts
					(xy 385.840986 -169.46753) (xy 382.564386 -169.46753) (xy 382.564386 -164.18433) (xy 385.840986 -164.18433)
				)
			)
		)
		(zone
			(layer "B.Cu")
			(hatch none 0.5)
			(connect_pads
				(clearance 0)
			)
			(min_thickness 0.25)
			(keepout
				(tracks allowed)
				(vias not_allowed)
				(pads allowed)
				(copperpour not_allowed)
				(footprints allowed)
			)
			(placement
				(enabled no)
				(sheetname "")
			)
			(fill
				(thermal_gap 0.5)
				(thermal_bridge_width 0.5)
				(island_removal_mode 0)
			)
			(polygon
				(pts
					(xy 385.840986 -161.46653) (xy 382.564386 -161.46653) (xy 382.564386 -156.18333) (xy 385.840986 -156.18333)
				)
			)
		)
		(zone
			(layer "B.Cu")
			(hatch none 0.5)
			(connect_pads
				(clearance 0)
			)
			(min_thickness 0.25)
			(keepout
				(tracks allowed)
				(vias not_allowed)
				(pads allowed)
				(copperpour not_allowed)
				(footprints allowed)
			)
			(placement
				(enabled no)
				(sheetname "")
			)
			(fill
				(thermal_gap 0.5)
				(thermal_bridge_width 0.5)
				(island_removal_mode 0)
			)
			(polygon
				(pts
					(xy 391.835386 -169.46753) (xy 388.558786 -169.46753) (xy 388.558786 -164.18433) (xy 391.835386 -164.18433)
				)
			)
		)
		(zone
			(layer "B.Cu")
			(hatch none 0.5)
			(connect_pads
				(clearance 0)
			)
			(min_thickness 0.25)
			(keepout
				(tracks allowed)
				(vias not_allowed)
				(pads allowed)
				(copperpour not_allowed)
				(footprints allowed)
			)
			(placement
				(enabled no)
				(sheetname "")
			)
			(fill
				(thermal_gap 0.5)
				(thermal_bridge_width 0.5)
				(island_removal_mode 0)
			)
			(polygon
				(pts
					(xy 391.835386 -161.46653) (xy 388.558786 -161.46653) (xy 388.558786 -156.18333) (xy 391.835386 -156.18333)
				)
			)
		)
	)
	(footprint ""
		(layer "F.Cu")
		(at 427.228 -38.989)
		(property "Reference" "R137"
			(at 0 0 0)
			(layer "F.SilkS")
			(hide yes)
			(effects
				(font
					(size 1.27 1.27)
				)
			)
		)
		(property "Value" ""
			(at 0 0 0)
			(layer "F.Fab")
			(effects
				(font
					(size 1.27 1.27)
				)
			)
		)
		(duplicate_pad_numbers_are_jumpers no)
		(fp_line
			(start -0.7874 -0.4064)
			(end 0.7874 -0.4064)
			(stroke
				(width 0.1524)
				(type default)
			)
			(layer "F.SilkS")
		)
		(fp_line
			(start -0.7874 0.4064)
			(end -0.7874 -0.4064)
			(stroke
				(width 0.1524)
				(type default)
			)
			(layer "F.SilkS")
		)
		(fp_line
			(start 0.7874 -0.4064)
			(end 0.7874 0.4064)
			(stroke
				(width 0.1524)
				(type default)
			)
			(layer "F.SilkS")
		)
		(fp_line
			(start 0.7874 0.4064)
			(end -0.7874 0.4064)
			(stroke
				(width 0.1524)
				(type default)
			)
			(layer "F.SilkS")
		)
		(fp_line
			(start -0.67945 -0.305054)
			(end -0.12065 -0.305054)
			(stroke
				(width 0.1)
				(type default)
			)
			(layer "F.Fab")
		)
		(fp_line
			(start -0.67945 0.3048)
			(end -0.67945 -0.305054)
			(stroke
				(width 0.1)
				(type default)
			)
			(layer "F.Fab")
		)
		(fp_line
			(start -0.12065 -0.305054)
			(end -0.12065 -0.2794)
			(stroke
				(width 0.1)
				(type default)
			)
			(layer "F.Fab")
		)
		(fp_line
			(start -0.12065 -0.2794)
			(end 0.12065 -0.2794)
			(stroke
				(width 0.1)
				(type default)
			)
			(layer "F.Fab")
		)
		(fp_line
			(start -0.12065 0.2794)
			(end -0.12065 0.3048)
			(stroke
				(width 0.1)
				(type default)
			)
			(layer "F.Fab")
		)
		(fp_line
			(start -0.12065 0.3048)
			(end -0.67945 0.3048)
			(stroke
				(width 0.1)
				(type default)
			)
			(layer "F.Fab")
		)
		(fp_line
			(start 0.120396 0.2794)
			(end -0.12065 0.2794)
			(stroke
				(width 0.1)
				(type default)
			)
			(layer "F.Fab")
		)
		(fp_line
			(start 0.120396 0.3048)
			(end 0.120396 0.2794)
			(stroke
				(width 0.1)
				(type default)
			)
			(layer "F.Fab")
		)
		(fp_line
			(start 0.12065 -0.3048)
			(end 0.67945 -0.3048)
			(stroke
				(width 0.1)
				(type default)
			)
			(layer "F.Fab")
		)
		(fp_line
			(start 0.12065 -0.2794)
			(end 0.12065 -0.3048)
			(stroke
				(width 0.1)
				(type default)
			)
			(layer "F.Fab")
		)
		(fp_line
			(start 0.67945 -0.3048)
			(end 0.67945 0.3048)
			(stroke
				(width 0.1)
				(type default)
			)
			(layer "F.Fab")
		)
		(fp_line
			(start 0.67945 0.3048)
			(end 0.120396 0.3048)
			(stroke
				(width 0.1)
				(type default)
			)
			(layer "F.Fab")
		)
		(pad "1" smd circle
			(at -0.40005 0)
			(size 0 0)
			(layers "F.Cu" "F.Mask" "F.Paste")
			(net "BOARD_ID_1")
		)
		(pad "2" smd circle
			(at 0.40005 0)
			(size 0 0)
			(layers "F.Cu" "F.Mask" "F.Paste")
			(net "GND")
		)
	)
	(footprint ""
		(layer "F.Cu")
		(at 304.546 -39.4462)
		(property "Reference" "PR5864"
			(at 0 0 0)
			(layer "F.SilkS")
			(hide yes)
			(effects
				(font
					(size 1.27 1.27)
				)
			)
		)
		(property "Value" ""
			(at 0 0 0)
			(layer "F.Fab")
			(effects
				(font
					(size 1.27 1.27)
				)
			)
		)
		(duplicate_pad_numbers_are_jumpers no)
		(fp_line
			(start -0.7874 -0.4064)
			(end 0.7874 -0.4064)
			(stroke
				(width 0.1524)
				(type default)
			)
			(layer "F.SilkS")
		)
		(fp_line
			(start -0.7874 0.4064)
			(end -0.7874 -0.4064)
			(stroke
				(width 0.1524)
				(type default)
			)
			(layer "F.SilkS")
		)
		(fp_line
			(start 0.7874 -0.4064)
			(end 0.7874 0.4064)
			(stroke
				(width 0.1524)
				(type default)
			)
			(layer "F.SilkS")
		)
		(fp_line
			(start 0.7874 0.4064)
			(end -0.7874 0.4064)
			(stroke
				(width 0.1524)
				(type default)
			)
			(layer "F.SilkS")
		)
		(fp_line
			(start -0.67945 -0.305054)
			(end -0.12065 -0.305054)
			(stroke
				(width 0.1)
				(type default)
			)
			(layer "F.Fab")
		)
		(fp_line
			(start -0.67945 0.3048)
			(end -0.67945 -0.305054)
			(stroke
				(width 0.1)
				(type default)
			)
			(layer "F.Fab")
		)
		(fp_line
			(start -0.12065 -0.305054)
			(end -0.12065 -0.2794)
			(stroke
				(width 0.1)
				(type default)
			)
			(layer "F.Fab")
		)
		(fp_line
			(start -0.12065 -0.2794)
			(end 0.12065 -0.2794)
			(stroke
				(width 0.1)
				(type default)
			)
			(layer "F.Fab")
		)
		(fp_line
			(start -0.12065 0.2794)
			(end -0.12065 0.3048)
			(stroke
				(width 0.1)
				(type default)
			)
			(layer "F.Fab")
		)
		(fp_line
			(start -0.12065 0.3048)
			(end -0.67945 0.3048)
			(stroke
				(width 0.1)
				(type default)
			)
			(layer "F.Fab")
		)
		(fp_line
			(start 0.120396 0.2794)
			(end -0.12065 0.2794)
			(stroke
				(width 0.1)
				(type default)
			)
			(layer "F.Fab")
		)
		(fp_line
			(start 0.120396 0.3048)
			(end 0.120396 0.2794)
			(stroke
				(width 0.1)
				(type default)
			)
			(layer "F.Fab")
		)
		(fp_line
			(start 0.12065 -0.3048)
			(end 0.67945 -0.3048)
			(stroke
				(width 0.1)
				(type default)
			)
			(layer "F.Fab")
		)
		(fp_line
			(start 0.12065 -0.2794)
			(end 0.12065 -0.3048)
			(stroke
				(width 0.1)
				(type default)
			)
			(layer "F.Fab")
		)
		(fp_line
			(start 0.67945 -0.3048)
			(end 0.67945 0.3048)
			(stroke
				(width 0.1)
				(type default)
			)
			(layer "F.Fab")
		)
		(fp_line
			(start 0.67945 0.3048)
			(end 0.120396 0.3048)
			(stroke
				(width 0.1)
				(type default)
			)
			(layer "F.Fab")
		)
		(pad "1" smd circle
			(at -0.40005 0)
			(size 0 0)
			(layers "F.Cu" "F.Mask" "F.Paste")
			(net "P52V_HS_4287_S2P")
		)
		(pad "2" smd circle
			(at 0.40005 0)
			(size 0 0)
			(layers "F.Cu" "F.Mask" "F.Paste")
			(net "P52V_HS_4287_S2N")
		)
	)
)
